(kicad_pcb
	(version 20260206)
	(generator "pcbnew")
	(generator_version "10.0")
	(general
		(thickness 1.6)
		(legacy_teardrops no)
	)
	(paper "A4")
	(title_block
		(title "Bryce Canyon_IOM_IOC_16318-2_OCP.brd")
		(comment 1 "Bryce Canyon / footprints 446-451 of 1605")
	)
	(layers
		(0 "F.Cu" signal "TOP")
		(4 "In1.Cu" signal "L2GND")
		(6 "In2.Cu" signal "L3")
		(8 "In3.Cu" signal "L4VCC")
		(10 "In4.Cu" signal "L5VCC")
		(12 "In5.Cu" signal "L6")
		(14 "In6.Cu" signal "L7GND")
		(2 "B.Cu" signal "BOTTOM")
		(9 "F.Adhes" user "F.Adhesive")
		(11 "B.Adhes" user "B.Adhesive")
		(13 "F.Paste" user "Package Geometry/Pastemask Top")
		(15 "B.Paste" user "Package Geometry/Pastemask Bottom")
		(5 "F.SilkS" user "Ref Des/Silkscreen Top")
		(7 "B.SilkS" user "Ref Des/Silkscreen Bottom")
		(1 "F.Mask" user "Board Geometry/Soldermask Top")
		(3 "B.Mask" user "Board Geometry/Soldermask Bottom")
		(17 "Dwgs.User" user "User.Drawings")
		(19 "Cmts.User" user "User.Comments")
		(21 "Eco1.User" user "User.Eco1")
		(23 "Eco2.User" user "User.Eco2")
		(25 "Edge.Cuts" user "Board Geometry/Outline")
		(27 "Margin" user)
		(31 "F.CrtYd" user "Package Geometry/Place Bound Top")
		(29 "B.CrtYd" user "Package Geometry/Place Bound Bottom")
		(35 "F.Fab" user "Ref Des/Assembly Top")
		(33 "B.Fab" user "Ref Des/Assembly Bottom")
	)
	(footprint ""
		(layer "F.Cu")
		(at 184.829704 -149.714966 180)
		(property "Reference" "C163"
			(at 0 0 180)
			(layer "F.SilkS")
			(hide yes)
			(effects
				(font
					(size 1.27 1.27)
				)
			)
		)
		(property "Value" "SC68P50V2JN-2-GP"
			(at 1.1811 -2.7051 180)
			(unlocked yes)
			(layer "F.Fab")
			(hide yes)
			(effects
				(font
					(size 1.016 1.016)
					(thickness 0.1524)
				)
			)
		)
		(property "Device Type" "C402H22"
			(at 1.1811 -4.2291 180)
			(unlocked yes)
			(layer "F.Fab")
			(hide yes)
			(effects
				(font
					(size 1.016 1.016)
					(thickness 0.1524)
				)
			)
		)
		(duplicate_pad_numbers_are_jumpers no)
		(fp_rect
			(start -0.4318 0.9525)
			(end 0.4318 -0.9525)
			(stroke
				(width 0)
				(type default)
			)
			(fill no)
			(layer "F.CrtYd")
		)
		(fp_rect
			(start -0.4318 0.9525)
			(end 0.4318 -0.9525)
			(stroke
				(width 0)
				(type default)
			)
			(fill no)
			(layer "F.Fab")
		)
		(pad "1" smd custom
			(at 0 -0.4445 180)
			(size 0.1524 0.1524)
			(layers "F.Cu" "F.Mask" "F.Paste")
			(net "P5V_VFB")
			(options
				(clearance outline)
				(anchor circle)
			)
			(primitives
				(gr_poly
					(pts
						(arc
							(start 0.3048 -0.2032)
							(mid 0.275042 -0.275042)
							(end 0.2032 -0.3048)
						)
						(arc
							(start -0.2032 -0.3048)
							(mid -0.275042 -0.275042)
							(end -0.3048 -0.2032)
						)
						(arc
							(start -0.3048 0.2032)
							(mid -0.275042 0.275042)
							(end -0.2032 0.3048)
						)
						(arc
							(start 0.2032 0.3048)
							(mid 0.275042 0.275042)
							(end 0.3048 0.2032)
						)
					)
					(width 0)
					(fill yes)
				)
			)
		)
		(pad "2" smd custom
			(at 0 0.4445 180)
			(size 0.1524 0.1524)
			(layers "F.Cu" "F.Mask" "F.Paste")
			(net "P5V_VFB_R")
			(options
				(clearance outline)
				(anchor circle)
			)
			(primitives
				(gr_poly
					(pts
						(arc
							(start 0.3048 -0.2032)
							(mid 0.275042 -0.275042)
							(end 0.2032 -0.3048)
						)
						(arc
							(start -0.2032 -0.3048)
							(mid -0.275042 -0.275042)
							(end -0.3048 -0.2032)
						)
						(arc
							(start -0.3048 0.2032)
							(mid -0.275042 0.275042)
							(end -0.2032 0.3048)
						)
						(arc
							(start 0.2032 0.3048)
							(mid 0.275042 0.275042)
							(end 0.3048 0.2032)
						)
					)
					(width 0)
					(fill yes)
				)
			)
		)
	)
	(footprint ""
		(layer "F.Cu")
		(at 188.2902 -48.387)
		(property "Reference" "R657"
			(at 0 0 0)
			(layer "F.SilkS")
			(hide yes)
			(effects
				(font
					(size 1.27 1.27)
				)
			)
		)
		(property "Value" "10KR2F-2-GP"
			(at 0.064008 -3.993896 0)
			(unlocked yes)
			(layer "F.Fab")
			(hide yes)
			(effects
				(font
					(size 1.016 1.016)
					(thickness 0.1524)
				)
			)
		)
		(property "Device Type" "R402H16"
			(at 0.064008 -5.517896 0)
			(unlocked yes)
			(layer "F.Fab")
			(hide yes)
			(effects
				(font
					(size 1.016 1.016)
					(thickness 0.1524)
				)
			)
		)
		(duplicate_pad_numbers_are_jumpers no)
		(fp_line
			(start -0.508 -0.9398)
			(end -0.508 0.9398)
			(stroke
				(width 0.1524)
				(type default)
			)
			(layer "F.SilkS")
		)
		(fp_line
			(start 0.508 -0.9398)
			(end -0.508 -0.9398)
			(stroke
				(width 0.1524)
				(type default)
			)
			(layer "F.SilkS")
		)
		(fp_rect
			(start -0.508 0.9398)
			(end 0.508 -0.9398)
			(stroke
				(width 0)
				(type default)
			)
			(fill no)
			(layer "F.CrtYd")
		)
		(fp_rect
			(start -0.508 0.9398)
			(end 0.508 -0.9398)
			(stroke
				(width 0)
				(type default)
			)
			(fill no)
			(layer "F.Fab")
		)
		(pad "1" smd custom
			(at 0 -0.4445)
			(size 0.1397 0.1397)
			(layers "F.Cu" "F.Mask" "F.Paste")
			(net "LSI_IDDT")
			(options
				(clearance outline)
				(anchor circle)
			)
			(primitives
				(gr_poly
					(pts
						(arc
							(start -0.1778 -0.2794)
							(mid -0.249642 -0.249642)
							(end -0.2794 -0.1778)
						)
						(arc
							(start -0.2794 0.1778)
							(mid -0.249642 0.249642)
							(end -0.1778 0.2794)
						)
						(arc
							(start 0.1778 0.2794)
							(mid 0.249642 0.249642)
							(end 0.2794 0.1778)
						)
						(arc
							(start 0.2794 -0.1778)
							(mid 0.249642 -0.249642)
							(end 0.1778 -0.2794)
						)
					)
					(width 0)
					(fill yes)
				)
			)
		)
		(pad "2" smd custom
			(at 0 0.4445)
			(size 0.1397 0.1397)
			(layers "F.Cu" "F.Mask" "F.Paste")
			(net "GND")
			(options
				(clearance outline)
				(anchor circle)
			)
			(primitives
				(gr_poly
					(pts
						(arc
							(start -0.1778 -0.2794)
							(mid -0.249642 -0.249642)
							(end -0.2794 -0.1778)
						)
						(arc
							(start -0.2794 0.1778)
							(mid -0.249642 0.249642)
							(end -0.1778 0.2794)
						)
						(arc
							(start 0.1778 0.2794)
							(mid 0.249642 0.249642)
							(end 0.2794 0.1778)
						)
						(arc
							(start 0.2794 -0.1778)
							(mid 0.249642 -0.249642)
							(end 0.1778 -0.2794)
						)
					)
					(width 0)
					(fill yes)
				)
			)
		)
	)
	(footprint ""
		(layer "F.Cu")
		(at 18.2372 -174.9298 180)
		(property "Reference" "C229"
			(at 0 0 180)
			(layer "F.SilkS")
			(hide yes)
			(effects
				(font
					(size 1.27 1.27)
				)
			)
		)
		(property "Value" "SC1U16V3KX-5GP"
			(at 0 -2.8194 180)
			(unlocked yes)
			(layer "F.Fab")
			(hide yes)
			(effects
				(font
					(size 1.016 1.016)
					(thickness 0.1524)
				)
			)
		)
		(property "Device Type" "C603H36"
			(at 0 -4.3434 180)
			(unlocked yes)
			(layer "F.Fab")
			(hide yes)
			(effects
				(font
					(size 1.016 1.016)
					(thickness 0.1524)
				)
			)
		)
		(duplicate_pad_numbers_are_jumpers no)
		(fp_line
			(start 0.508 0)
			(end -0.508 0)
			(stroke
				(width 0.2032)
				(type default)
			)
			(layer "F.SilkS")
		)
		(fp_rect
			(start -0.5842 1.3335)
			(end 0.5842 -1.3335)
			(stroke
				(width 0)
				(type default)
			)
			(fill no)
			(layer "F.CrtYd")
		)
		(fp_rect
			(start -0.5842 1.3335)
			(end 0.5842 -1.3335)
			(stroke
				(width 0)
				(type default)
			)
			(fill no)
			(layer "F.Fab")
		)
		(pad "1" smd custom
			(at 0 -0.762 180)
			(size 0.2159 0.2159)
			(layers "F.Cu" "F.Mask" "F.Paste")
			(net "TPS74801_P1V2_STBY_BIAS")
			(options
				(clearance outline)
				(anchor circle)
			)
			(primitives
				(gr_poly
					(pts
						(arc
							(start -0.3302 -0.4318)
							(mid -0.402042 -0.402042)
							(end -0.4318 -0.3302)
						)
						(arc
							(start -0.4318 0.3302)
							(mid -0.402042 0.402042)
							(end -0.3302 0.4318)
						)
						(arc
							(start 0.3302 0.4318)
							(mid 0.402042 0.402042)
							(end 0.4318 0.3302)
						)
						(arc
							(start 0.4318 -0.3302)
							(mid 0.402042 -0.402042)
							(end 0.3302 -0.4318)
						)
					)
					(width 0)
					(fill yes)
				)
			)
		)
		(pad "2" smd custom
			(at 0 0.762 180)
			(size 0.2159 0.2159)
			(layers "F.Cu" "F.Mask" "F.Paste")
			(net "GND")
			(options
				(clearance outline)
				(anchor circle)
			)
			(primitives
				(gr_poly
					(pts
						(arc
							(start -0.3302 -0.4318)
							(mid -0.402042 -0.402042)
							(end -0.4318 -0.3302)
						)
						(arc
							(start -0.4318 0.3302)
							(mid -0.402042 0.402042)
							(end -0.3302 0.4318)
						)
						(arc
							(start 0.3302 0.4318)
							(mid 0.402042 0.402042)
							(end 0.4318 0.3302)
						)
						(arc
							(start 0.4318 -0.3302)
							(mid 0.402042 -0.402042)
							(end 0.3302 -0.4318)
						)
					)
					(width 0)
					(fill yes)
				)
			)
		)
	)
	(footprint ""
		(layer "F.Cu")
		(at 86.599268 -134.677404)
		(property "Reference" "R134"
			(at 0 0 0)
			(layer "F.SilkS")
			(hide yes)
			(effects
				(font
					(size 1.27 1.27)
				)
			)
		)
		(property "Value" "8K2R2J-3-GP"
			(at 0.064008 -3.993896 0)
			(unlocked yes)
			(layer "F.Fab")
			(hide yes)
			(effects
				(font
					(size 1.016 1.016)
					(thickness 0.1524)
				)
			)
		)
		(property "Device Type" "R402H16"
			(at 0.064008 -5.517896 0)
			(unlocked yes)
			(layer "F.Fab")
			(hide yes)
			(effects
				(font
					(size 1.016 1.016)
					(thickness 0.1524)
				)
			)
		)
		(duplicate_pad_numbers_are_jumpers no)
		(fp_line
			(start -0.508 -0.9398)
			(end -0.508 0.9398)
			(stroke
				(width 0.1524)
				(type default)
			)
			(layer "F.SilkS")
		)
		(fp_line
			(start 0.508 -0.9398)
			(end -0.508 -0.9398)
			(stroke
				(width 0.1524)
				(type default)
			)
			(layer "F.SilkS")
		)
		(fp_rect
			(start -0.508 0.9398)
			(end 0.508 -0.9398)
			(stroke
				(width 0)
				(type default)
			)
			(fill no)
			(layer "F.CrtYd")
		)
		(fp_rect
			(start -0.508 0.9398)
			(end 0.508 -0.9398)
			(stroke
				(width 0)
				(type default)
			)
			(fill no)
			(layer "F.Fab")
		)
		(pad "1" smd custom
			(at 0 -0.4445)
			(size 0.1397 0.1397)
			(layers "F.Cu" "F.Mask" "F.Paste")
			(net "P3V3_STBY")
			(options
				(clearance outline)
				(anchor circle)
			)
			(primitives
				(gr_poly
					(pts
						(arc
							(start -0.1778 -0.2794)
							(mid -0.249642 -0.249642)
							(end -0.2794 -0.1778)
						)
						(arc
							(start -0.2794 0.1778)
							(mid -0.249642 0.249642)
							(end -0.1778 0.2794)
						)
						(arc
							(start 0.1778 0.2794)
							(mid 0.249642 0.249642)
							(end 0.2794 0.1778)
						)
						(arc
							(start 0.2794 -0.1778)
							(mid 0.249642 -0.249642)
							(end 0.1778 -0.2794)
						)
					)
					(width 0)
					(fill yes)
				)
			)
		)
		(pad "2" smd custom
			(at 0 0.4445)
			(size 0.1397 0.1397)
			(layers "F.Cu" "F.Mask" "F.Paste")
			(net "EEPROM_A1")
			(options
				(clearance outline)
				(anchor circle)
			)
			(primitives
				(gr_poly
					(pts
						(arc
							(start -0.1778 -0.2794)
							(mid -0.249642 -0.249642)
							(end -0.2794 -0.1778)
						)
						(arc
							(start -0.2794 0.1778)
							(mid -0.249642 0.249642)
							(end -0.1778 0.2794)
						)
						(arc
							(start 0.1778 0.2794)
							(mid 0.249642 0.249642)
							(end 0.2794 0.1778)
						)
						(arc
							(start 0.2794 -0.1778)
							(mid 0.249642 -0.249642)
							(end 0.1778 -0.2794)
						)
					)
					(width 0)
					(fill yes)
				)
			)
		)
	)
	(footprint ""
		(layer "F.Cu")
		(at 201.5236 -85.7758 135)
		(property "Reference" "VIA18"
			(at 0 0 135)
			(layer "F.SilkS")
			(hide yes)
			(effects
				(font
					(size 1.27 1.27)
				)
			)
		)
		(property "Value" "85OHM-8L-1D6MM-L16L18-GP"
			(at 4.064105 0.609655 135)
			(unlocked yes)
			(layer "F.Fab")
			(hide yes)
			(effects
				(font
					(size 1.016 1.016)
					(thickness 0.1524)
				)
			)
		)
		(property "Device Type" "VIA-PCIE-4P-368076"
			(at 4.064105 -0.914474 135)
			(unlocked yes)
			(layer "F.Fab")
			(hide yes)
			(effects
				(font
					(size 1.016 1.016)
					(thickness 0.1524)
				)
			)
		)
		(duplicate_pad_numbers_are_jumpers no)
		(fp_poly
			(pts
				(xy -1.841491 -0.381057) (xy 1.841509 -0.381058) (xy 1.841508 0.380942) (xy -1.841491 0.380942)
			)
			(stroke
				(width 0)
				(type default)
			)
			(fill no)
			(layer "F.CrtYd")
		)
		(fp_poly
			(pts
				(xy -1.841491 -0.381057) (xy 1.841509 -0.381058) (xy 1.841508 0.380942) (xy -1.841491 0.380942)
			)
			(stroke
				(width 0)
				(type default)
			)
			(fill no)
			(layer "F.Fab")
		)
		(pad "1" thru_hole circle
			(at -1.460499 0 135)
			(size 0.508 0.508)
			(drill 0.254)
			(layers "*.Cu" "*.Mask")
			(remove_unused_layers no)
			(net "GND")
			(clearance 0.127)
			(thermal_gap 0.127)
		)
		(pad "2" thru_hole circle
			(at -0.4445 0 135)
			(size 0.508 0.508)
			(drill 0.254)
			(layers "*.Cu" "*.Mask")
			(remove_unused_layers no)
			(net "PCIE_COMP_TO_IOM_9_DP")
			(clearance 0.127)
			(thermal_gap 0.127)
		)
		(pad "3" thru_hole circle
			(at 0.4445 0 135)
			(size 0.508 0.508)
			(drill 0.254)
			(layers "*.Cu" "*.Mask")
			(remove_unused_layers no)
			(net "PCIE_COMP_TO_IOM_9_DN")
			(clearance 0.127)
			(thermal_gap 0.127)
		)
		(pad "4" thru_hole circle
			(at 1.460499 0 135)
			(size 0.508 0.508)
			(drill 0.254)
			(layers "*.Cu" "*.Mask")
			(remove_unused_layers no)
			(net "GND")
			(clearance 0.127)
			(thermal_gap 0.127)
		)
	)
	(footprint ""
		(layer "F.Cu")
		(at 169.1894 -171.0436 -90)
		(property "Reference" "C168"
			(at 0 0 270)
			(layer "F.SilkS")
			(hide yes)
			(effects
				(font
					(size 1.27 1.27)
				)
			)
		)
		(property "Value" "ST150U16VDM-3-GP"
			(at 0 -9.6012 270)
			(unlocked yes)
			(layer "F.Fab")
			(hide yes)
			(effects
				(font
					(size 1.016 1.016)
					(thickness 0.1524)
				)
			)
		)
		(property "Device Type" "CT7343H119"
			(at 0 -11.1252 270)
			(unlocked yes)
			(layer "F.Fab")
			(hide yes)
			(effects
				(font
					(size 1.016 1.016)
					(thickness 0.1524)
				)
			)
		)
		(duplicate_pad_numbers_are_jumpers no)
		(fp_line
			(start -2.286 4.8768)
			(end -2.286 2.032)
			(stroke
				(width 0.1524)
				(type default)
			)
			(layer "F.SilkS")
		)
		(fp_line
			(start 2.286 4.8768)
			(end -2.286 4.8768)
			(stroke
				(width 0.1524)
				(type default)
			)
			(layer "F.SilkS")
		)
		(fp_line
			(start 2.286 2.032)
			(end 2.286 4.8768)
			(stroke
				(width 0.1524)
				(type default)
			)
			(layer "F.SilkS")
		)
		(fp_line
			(start 2.286 -2.032)
			(end 2.286 -4.8768)
			(stroke
				(width 0.1524)
				(type default)
			)
			(layer "F.SilkS")
		)
		(fp_line
			(start 2.1082 -4.699)
			(end -2.1082 -4.699)
			(stroke
				(width 0.508)
				(type default)
			)
			(layer "F.SilkS")
		)
		(fp_line
			(start -2.286 -4.8768)
			(end -2.286 -2.032)
			(stroke
				(width 0.1524)
				(type default)
			)
			(layer "F.SilkS")
		)
		(fp_line
			(start 2.286 -4.8768)
			(end -2.286 -4.8768)
			(stroke
				(width 0.1524)
				(type default)
			)
			(layer "F.SilkS")
		)
		(fp_rect
			(start -2.1463 3.6449)
			(end 2.1463 -3.6449)
			(stroke
				(width 0)
				(type default)
			)
			(fill no)
			(layer "F.CrtYd")
		)
		(fp_poly
			(pts
				(xy -2.54 4.953) (xy -2.54 4.2926) (xy -3.81 4.2926) (xy -3.81 -4.2926) (xy -2.54 -4.2926) (xy -2.54 -4.953)
				(xy 2.54 -4.953) (xy 2.54 -4.2926) (xy 3.81 -4.2926) (xy 3.81 -1.6256) (xy 2.1463 -1.6256) (xy 2.1463 -3.6449)
				(xy -2.1463 -3.6449) (xy -2.1463 3.6449) (xy 2.1463 3.6449) (xy 2.1463 -1.6129) (xy 3.81 -1.6129)
				(xy 3.81 4.2926) (xy 2.54 4.2926) (xy 2.54 4.953)
			)
			(stroke
				(width 0)
				(type default)
			)
			(fill no)
			(layer "F.CrtYd")
		)
		(fp_rect
			(start -2.54 4.953)
			(end 2.54 -4.953)
			(stroke
				(width 0)
				(type default)
			)
			(fill no)
			(layer "F.Fab")
		)
		(fp_rect
			(start -3.81 4.2926)
			(end -2.54 -4.2926)
			(stroke
				(width 0)
				(type default)
			)
			(fill no)
			(layer "F.Fab")
		)
		(fp_rect
			(start 2.54 4.2926)
			(end 3.81 -4.2926)
			(stroke
				(width 0)
				(type default)
			)
			(fill no)
			(layer "F.Fab")
		)
		(pad "1" smd rect
			(at 0 -3.1496 270)
			(size 2.413 2.286)
			(layers "F.Cu" "F.Mask" "F.Paste")
			(net "P5V_STBY")
		)
		(pad "2" smd rect
			(at 0 3.1496 270)
			(size 2.413 2.286)
			(layers "F.Cu" "F.Mask" "F.Paste")
			(net "GND")
		)
		(zone
			(layer "F.Cu")
			(hatch none 0.5)
			(connect_pads
				(clearance 0)
			)
			(min_thickness 0.25)
			(keepout
				(tracks allowed)
				(vias not_allowed)
				(pads allowed)
				(copperpour not_allowed)
				(footprints allowed)
			)
			(placement
				(enabled no)
				(sheetname "")
			)
			(fill
				(thermal_gap 0.5)
				(thermal_bridge_width 0.5)
				(island_removal_mode 0)
			)
			(polygon
				(pts
					(xy 164.592 -172.5549) (xy 164.592 -169.5323) (xy 167.4876 -169.5323) (xy 167.8178 -169.5323) (xy 167.8178 -172.5549)
					(xy 167.4876 -172.5549)
				)
			)
		)
		(zone
			(layer "F.Cu")
			(hatch none 0.5)
			(connect_pads
				(clearance 0)
			)
			(min_thickness 0.25)
			(keepout
				(tracks allowed)
				(vias not_allowed)
				(pads allowed)
				(copperpour not_allowed)
				(footprints allowed)
			)
			(placement
				(enabled no)
				(sheetname "")
			)
			(fill
				(thermal_gap 0.5)
				(thermal_bridge_width 0.5)
				(island_removal_mode 0)
			)
			(polygon
				(pts
					(xy 170.8785 -169.5323) (xy 173.7868 -169.5323) (xy 173.7868 -172.5549) (xy 170.8912 -172.5549)
					(xy 170.561 -172.5549) (xy 170.561 -169.5323)
				)
			)
		)
	)
)
